(kicad_pcb
	(version 20241229)
	(generator "pcbnew")
	(generator_version "9.0")
	(general
		(thickness 1.62)
		(legacy_teardrops no)
	)
	(paper "A4")
	(title_block
		(title "OCuLink to 10GbE adapter")
		(date "2026-02-23")
		(rev "1.1.0")
		(company "Antmicro Ltd")
		(comment 1 "www.antmicro.com")
		(comment 9 "footprints 84-89 of 510")
	)
	(layers
		(0 "F.Cu" signal)
		(4 "In1.Cu" signal)
		(6 "In2.Cu" signal)
		(8 "In3.Cu" signal)
		(10 "In4.Cu" signal)
		(12 "In5.Cu" signal)
		(14 "In6.Cu" signal)
		(2 "B.Cu" signal)
		(9 "F.Adhes" user "F.Adhesive")
		(11 "B.Adhes" user "B.Adhesive")
		(13 "F.Paste" user)
		(15 "B.Paste" user)
		(5 "F.SilkS" user "F.Silkscreen")
		(7 "B.SilkS" user "B.Silkscreen")
		(1 "F.Mask" user)
		(3 "B.Mask" user)
		(17 "Dwgs.User" user "User.Drawings")
		(19 "Cmts.User" user "User.Comments")
		(21 "Eco1.User" user "User.Eco1")
		(23 "Eco2.User" user "User.Eco2")
		(25 "Edge.Cuts" user)
		(27 "Margin" user)
		(31 "F.CrtYd" user "F.Courtyard")
		(29 "B.CrtYd" user "B.Courtyard")
		(35 "F.Fab" user)
		(33 "B.Fab" user)
	)
	(footprint "antmicro-footprints:C_0603_1608Metric"
		(layer "F.Cu")
		(at 97.9 100.65 180)
		(descr "Capacitor SMD 0603")
		(tags "capacitor 0603")
		(property "Reference" "C148"
			(at -3.75 0.35 0)
			(layer "F.SilkS")
			(effects
				(font
					(size 0.7 0.7)
					(thickness 0.15)
				)
				(justify left top)
			)
		)
		(property "Value" "C_10u_10V_X7R_0603"
			(at -1.42757 1.770288 0)
			(layer "F.Fab")
			(hide yes)
			(effects
				(font
					(size 0.7 0.7)
					(thickness 0.15)
				)
				(justify right top)
			)
		)
		(property "Datasheet" "https://www.murata.com/products/productdetail?partno=GRM188Z71A106KA73%23"
			(at 0 0 0)
			(layer "F.Fab")
			(hide yes)
			(effects
				(font
					(size 1.27 1.27)
					(thickness 0.15)
				)
			)
		)
		(property "Description" "SMD Multilayer Ceramic Capacitor,  10µF, 10V, 0603, ±10%, X7R"
			(at 0 0 0)
			(layer "F.Fab")
			(hide yes)
			(effects
				(font
					(size 1.27 1.27)
					(thickness 0.15)
				)
			)
		)
		(property "MPN" "GRM188Z71A106KA73D"
			(at 0 0 180)
			(unlocked yes)
			(layer "F.Fab")
			(hide yes)
			(effects
				(font
					(size 1 1)
					(thickness 0.15)
				)
			)
		)
		(property "Val" "10u"
			(at 0 0 180)
			(unlocked yes)
			(layer "F.Fab")
			(hide yes)
			(effects
				(font
					(size 1 1)
					(thickness 0.15)
				)
			)
		)
		(property "Voltage" "10V"
			(at 0 0 180)
			(unlocked yes)
			(layer "F.Fab")
			(hide yes)
			(effects
				(font
					(size 1 1)
					(thickness 0.15)
				)
			)
		)
		(property "Dielectric" "X7R"
			(at 0 0 180)
			(unlocked yes)
			(layer "F.Fab")
			(hide yes)
			(effects
				(font
					(size 1 1)
					(thickness 0.15)
				)
			)
		)
		(property "Manufacturer" "Murata"
			(at 0 0 180)
			(unlocked yes)
			(layer "F.Fab")
			(hide yes)
			(effects
				(font
					(size 1 1)
					(thickness 0.15)
				)
			)
		)
		(property "License" "Apache-2.0"
			(at 0 0 180)
			(unlocked yes)
			(layer "F.Fab")
			(hide yes)
			(effects
				(font
					(size 1 1)
					(thickness 0.15)
				)
			)
		)
		(property "Author" "Antmicro"
			(at 0 0 180)
			(unlocked yes)
			(layer "F.Fab")
			(hide yes)
			(effects
				(font
					(size 1 1)
					(thickness 0.15)
				)
			)
		)
		(sheetname "/X710-AT2 power/")
		(sheetfile "x710-at2-power.kicad_sch")
		(attr smd)
		(fp_line
			(start -0.15 0.4)
			(end 0.15 0.4)
			(stroke
				(width 0.15)
				(type solid)
			)
			(layer "F.SilkS")
		)
		(fp_line
			(start -0.15 -0.4)
			(end 0.15 -0.4)
			(stroke
				(width 0.15)
				(type solid)
			)
			(layer "F.SilkS")
		)
		(fp_rect
			(start -1.25 -0.65)
			(end 1.25 0.65)
			(stroke
				(width 0.05)
				(type solid)
			)
			(fill no)
			(layer "F.CrtYd")
		)
		(fp_rect
			(start -0.8 -0.4)
			(end 0.8 0.4)
			(stroke
				(width 0.15)
				(type solid)
			)
			(fill no)
			(layer "F.Fab")
		)
		(pad "1" smd roundrect
			(at -0.7 0 180)
			(size 0.8 1)
			(layers "F.Cu" "F.Mask" "F.Paste")
			(roundrect_rratio 0.2)
			(net 28 "GND")
			(pintype "passive")
		)
		(pad "2" smd roundrect
			(at 0.7 0 180)
			(size 0.8 1)
			(layers "F.Cu" "F.Mask" "F.Paste")
			(roundrect_rratio 0.2)
			(net 7 "+3V3")
			(pintype "passive")
		)
	)
	(footprint "antmicro-footprints:C_0402_1005Metric"
		(layer "F.Cu")
		(at 73.849999 81.039994 180)
		(descr "Capacitor SMD 0402")
		(tags "capacitor SMD 0402")
		(property "Reference" "C6"
			(at 2.349999 8.089994 0)
			(layer "F.SilkS")
			(effects
				(font
					(size 0.7 0.7)
					(thickness 0.15)
				)
				(justify right top)
			)
		)
		(property "Value" "C_1u_25V_0402"
			(at -1.022927 2.155213 0)
			(layer "F.Fab")
			(hide yes)
			(effects
				(font
					(size 0.7 0.7)
					(thickness 0.15)
				)
				(justify right top)
			)
		)
		(property "Datasheet" "https://www.murata.com/products/productdetail?partno=GRM155R61E105KE11%23"
			(at 0 0 0)
			(layer "F.Fab")
			(hide yes)
			(effects
				(font
					(size 1.27 1.27)
					(thickness 0.15)
				)
			)
		)
		(property "Description" "SMD Multilayer Ceramic Capacitor, 1 µF, 25 V, 0402 [1005 Metric], ± 10%, X5R, GRM Series"
			(at 0 0 0)
			(layer "F.Fab")
			(hide yes)
			(effects
				(font
					(size 1.27 1.27)
					(thickness 0.15)
				)
			)
		)
		(property "MPN" "GRM155R61E105KE11J"
			(at 0 0 180)
			(unlocked yes)
			(layer "F.Fab")
			(hide yes)
			(effects
				(font
					(size 1 1)
					(thickness 0.15)
				)
			)
		)
		(property "Manufacturer" "Murata"
			(at 0 0 180)
			(unlocked yes)
			(layer "F.Fab")
			(hide yes)
			(effects
				(font
					(size 1 1)
					(thickness 0.15)
				)
			)
		)
		(property "License" "Apache-2.0"
			(at 0 0 180)
			(unlocked yes)
			(layer "F.Fab")
			(hide yes)
			(effects
				(font
					(size 1 1)
					(thickness 0.15)
				)
			)
		)
		(property "Author" "Antmicro"
			(at 0 0 180)
			(unlocked yes)
			(layer "F.Fab")
			(hide yes)
			(effects
				(font
					(size 1 1)
					(thickness 0.15)
				)
			)
		)
		(property "Val" "1u"
			(at 0 0 180)
			(unlocked yes)
			(layer "F.Fab")
			(hide yes)
			(effects
				(font
					(size 1 1)
					(thickness 0.15)
				)
			)
		)
		(property "Voltage" "25V"
			(at 0 0 180)
			(unlocked yes)
			(layer "F.Fab")
			(hide yes)
			(effects
				(font
					(size 1 1)
					(thickness 0.15)
				)
			)
		)
		(property "Dielectric" "X5R"
			(at 0 0 180)
			(unlocked yes)
			(layer "F.Fab")
			(hide yes)
			(effects
				(font
					(size 1 1)
					(thickness 0.15)
				)
			)
		)
		(sheetname "/Power/")
		(sheetfile "power.kicad_sch")
		(attr smd)
		(fp_rect
			(start -0.925 -0.47)
			(end 0.925 0.47)
			(stroke
				(width 0.05)
				(type default)
			)
			(fill no)
			(layer "F.CrtYd")
		)
		(fp_line
			(start 0.504 0.248)
			(end -0.494 0.248)
			(stroke
				(width 0.15)
				(type solid)
			)
			(layer "F.Fab")
		)
		(fp_line
			(start 0.504 -0.25)
			(end 0.504 0.248)
			(stroke
				(width 0.15)
				(type solid)
			)
			(layer "F.Fab")
		)
		(fp_line
			(start -0.494 0.248)
			(end -0.494 -0.25)
			(stroke
				(width 0.15)
				(type solid)
			)
			(layer "F.Fab")
		)
		(fp_line
			(start -0.494 -0.25)
			(end 0.504 -0.25)
			(stroke
				(width 0.15)
				(type solid)
			)
			(layer "F.Fab")
		)
		(pad "1" smd roundrect
			(at -0.48 0 180)
			(size 0.59 0.64)
			(layers "F.Cu" "F.Mask" "F.Paste")
			(roundrect_rratio 0.25)
			(net 28 "GND")
			(pintype "passive")
		)
		(pad "2" smd roundrect
			(at 0.48 0 180)
			(size 0.59 0.64)
			(layers "F.Cu" "F.Mask" "F.Paste")
			(roundrect_rratio 0.25)
			(net 315 "/Power/3V3_VCC")
			(pintype "passive")
		)
	)
	(footprint "antmicro-footprints:R_0402_1005Metric"
		(layer "F.Cu")
		(at 111.15 106.55 90)
		(descr "Resistor SMD 0402")
		(tags "resistor SMD 0402")
		(property "Reference" "R176"
			(at -0.1 -2.55 90)
			(layer "F.SilkS")
			(effects
				(font
					(size 0.7 0.7)
					(thickness 0.15)
				)
				(justify left bottom)
			)
		)
		(property "Value" "R_0R_0402"
			(at -1.011843 1.772046 90)
			(layer "F.Fab")
			(hide yes)
			(effects
				(font
					(size 0.7 0.7)
					(thickness 0.15)
				)
				(justify left bottom)
			)
		)
		(property "Datasheet" "https://industrial.panasonic.com/cdbs/www-data/pdf/RDA0000/AOA0000C301.pdf"
			(at 0 0 90)
			(layer "F.Fab")
			(hide yes)
			(effects
				(font
					(size 1.27 1.27)
					(thickness 0.15)
				)
			)
		)
		(property "Description" "SMD Chip Resistor, Jumper, 0 ohm, 100 mW, 0402 [1005 Metric], Thick Film, General Purpose"
			(at 0 0 90)
			(layer "F.Fab")
			(hide yes)
			(effects
				(font
					(size 1.27 1.27)
					(thickness 0.15)
				)
			)
		)
		(property "MPN" "ERJ2GE0R00X"
			(at 0 0 90)
			(unlocked yes)
			(layer "F.Fab")
			(hide yes)
			(effects
				(font
					(size 1 1)
					(thickness 0.15)
				)
			)
		)
		(property "Manufacturer" "Panasonic"
			(at 0 0 90)
			(unlocked yes)
			(layer "F.Fab")
			(hide yes)
			(effects
				(font
					(size 1 1)
					(thickness 0.15)
				)
			)
		)
		(property "License" "Apache-2.0"
			(at 0 0 90)
			(unlocked yes)
			(layer "F.Fab")
			(hide yes)
			(effects
				(font
					(size 1 1)
					(thickness 0.15)
				)
			)
		)
		(property "Author" "Antmicro"
			(at 0 0 90)
			(unlocked yes)
			(layer "F.Fab")
			(hide yes)
			(effects
				(font
					(size 1 1)
					(thickness 0.15)
				)
			)
		)
		(property "Val" "0R"
			(at 0 0 90)
			(unlocked yes)
			(layer "F.Fab")
			(hide yes)
			(effects
				(font
					(size 1 1)
					(thickness 0.15)
				)
			)
		)
		(property "Tolerance" "~"
			(at 0 0 90)
			(unlocked yes)
			(layer "F.Fab")
			(hide yes)
			(effects
				(font
					(size 1 1)
					(thickness 0.15)
				)
			)
		)
		(property "Current" "1A"
			(at 0 0 90)
			(unlocked yes)
			(layer "F.Fab")
			(hide yes)
			(effects
				(font
					(size 1 1)
					(thickness 0.15)
				)
			)
		)
		(sheetname "/Fan controller/")
		(sheetfile "fan-controller.kicad_sch")
		(attr smd exclude_from_pos_files exclude_from_bom dnp)
		(fp_rect
			(start -0.925 -0.47)
			(end 0.925 0.47)
			(stroke
				(width 0.05)
				(type default)
			)
			(fill no)
			(layer "F.CrtYd")
		)
		(fp_rect
			(start -0.5 -0.25)
			(end 0.5 0.25)
			(stroke
				(width 0.15)
				(type solid)
			)
			(fill no)
			(layer "F.Fab")
		)
		(pad "1" smd roundrect
			(at -0.48 0 90)
			(size 0.59 0.64)
			(layers "F.Cu" "F.Mask" "F.Paste")
			(roundrect_rratio 0.25)
			(net 28 "GND")
			(pintype "passive")
		)
		(pad "2" smd roundrect
			(at 0.48 0 90)
			(size 0.59 0.64)
			(layers "F.Cu" "F.Mask" "F.Paste")
			(roundrect_rratio 0.25)
			(net 398 "/Fan controller/D0")
			(pintype "passive")
		)
	)
	(footprint "antmicro-footprints:MP_Pad6mm_Drill3.2mm"
		(layer "F.Cu")
		(at 56.75 54.250001)
		(property "Reference" "MP4"
			(at -3.8 -2.900001 0)
			(layer "F.SilkS")
			(hide yes)
			(effects
				(font
					(size 0.7 0.7)
					(thickness 0.15)
				)
				(justify left bottom)
			)
		)
		(property "Value" "MP_Pad6mm_Drill3.2mm"
			(at 0 3.9 0)
			(layer "F.Fab")
			(hide yes)
			(effects
				(font
					(size 0.7 0.7)
					(thickness 0.15)
				)
				(justify left bottom)
			)
		)
		(property "Description" "Mechanical part"
			(at 0 0 0)
			(layer "F.Fab")
			(hide yes)
			(effects
				(font
					(size 1.27 1.27)
					(thickness 0.15)
				)
			)
		)
		(property "Author" "Antmicro"
			(at 0 0 0)
			(unlocked yes)
			(layer "F.Fab")
			(hide yes)
			(effects
				(font
					(size 1 1)
					(thickness 0.15)
				)
			)
		)
		(property "License" "Apache-2.0"
			(at 0 0 0)
			(unlocked yes)
			(layer "F.Fab")
			(hide yes)
			(effects
				(font
					(size 1 1)
					(thickness 0.15)
				)
			)
		)
		(sheetname "/")
		(sheetfile "oculink-to-10gbe-adapter.kicad_sch")
		(attr exclude_from_pos_files exclude_from_bom)
		(fp_circle
			(center 0 0)
			(end 3.25 0)
			(stroke
				(width 0.05)
				(type default)
			)
			(fill no)
			(layer "F.CrtYd")
		)
		(pad "1" thru_hole circle
			(at 0 0)
			(size 6 6)
			(drill 3.2)
			(layers "*.Cu" "*.Mask")
			(remove_unused_layers no)
			(net 28 "GND")
			(pintype "passive")
		)
	)
	(footprint "antmicro-footprints:SOD-523"
		(layer "F.Cu")
		(at 111.325 108.405 180)
		(property "Reference" "D13"
			(at -1.125 -0.695 0)
			(layer "F.SilkS")
			(effects
				(font
					(size 0.7 0.7)
					(thickness 0.15)
				)
				(justify right top)
			)
		)
		(property "Value" "PESD5Z5_0F"
			(at 0 1.499 0)
			(layer "F.Fab")
			(hide yes)
			(effects
				(font
					(size 0.7 0.7)
					(thickness 0.15)
				)
				(justify right top)
			)
		)
		(property "Datasheet" "https://assets.nexperia.com/documents/data-sheet/PESD5Z5_0.pdf"
			(at 0 0 0)
			(layer "F.Fab")
			(hide yes)
			(effects
				(font
					(size 1.27 1.27)
					(thickness 0.15)
				)
			)
		)
		(property "Description" "Unidirectional TVS, 30 kV,  SOD-523, 5 V, 89 pF"
			(at 0 0 0)
			(layer "F.Fab")
			(hide yes)
			(effects
				(font
					(size 1.27 1.27)
					(thickness 0.15)
				)
			)
		)
		(property "Manufacturer" "Nexperia"
			(at 0 0 180)
			(unlocked yes)
			(layer "F.Fab")
			(hide yes)
			(effects
				(font
					(size 1 1)
					(thickness 0.15)
				)
			)
		)
		(property "MPN" "PESD5Z5.0F"
			(at 0 0 180)
			(unlocked yes)
			(layer "F.Fab")
			(hide yes)
			(effects
				(font
					(size 1 1)
					(thickness 0.15)
				)
			)
		)
		(property "Author" "Antmicro"
			(at 0 0 180)
			(unlocked yes)
			(layer "F.Fab")
			(hide yes)
			(effects
				(font
					(size 1 1)
					(thickness 0.15)
				)
			)
		)
		(property "License" "Apache-2.0"
			(at 0 0 180)
			(unlocked yes)
			(layer "F.Fab")
			(hide yes)
			(effects
				(font
					(size 1 1)
					(thickness 0.15)
				)
			)
		)
		(sheetname "/Fan controller/")
		(sheetfile "fan-controller.kicad_sch")
		(attr smd exclude_from_pos_files exclude_from_bom dnp)
		(fp_line
			(start -0.35 -0.5)
			(end -0.35 0.5)
			(stroke
				(width 0.15)
				(type solid)
			)
			(layer "F.SilkS")
		)
		(fp_rect
			(start -1 -0.6)
			(end 1 0.6)
			(stroke
				(width 0.05)
				(type solid)
			)
			(fill no)
			(layer "F.CrtYd")
		)
		(fp_line
			(start 0.65 -0.425)
			(end 0.65 0.423)
			(stroke
				(width 0.15)
				(type solid)
			)
			(layer "F.Fab")
		)
		(fp_line
			(start -0.35 -0.4)
			(end -0.35 0.4)
			(stroke
				(width 0.15)
				(type solid)
			)
			(layer "F.Fab")
		)
		(fp_line
			(start -0.652 0.423)
			(end 0.65 0.423)
			(stroke
				(width 0.15)
				(type solid)
			)
			(layer "F.Fab")
		)
		(fp_line
			(start -0.652 0.423)
			(end -0.652 -0.425)
			(stroke
				(width 0.15)
				(type solid)
			)
			(layer "F.Fab")
		)
		(fp_line
			(start -0.652 -0.425)
			(end 0.65 -0.425)
			(stroke
				(width 0.15)
				(type solid)
			)
			(layer "F.Fab")
		)
		(pad "1" smd roundrect
			(at -0.701 0 180)
			(size 0.5 0.6)
			(layers "F.Cu" "F.Mask" "F.Paste")
			(roundrect_rratio 0.25)
			(net 390 "/Fan controller/PWM")
			(pinfunction "C")
			(pintype "passive")
		)
		(pad "2" smd roundrect
			(at 0.699 0 180)
			(size 0.5 0.6)
			(layers "F.Cu" "F.Mask" "F.Paste")
			(roundrect_rratio 0.25)
			(net 28 "GND")
			(pinfunction "A")
			(pintype "passive")
		)
	)
	(footprint "antmicro-footprints:C_0603_1608Metric_EIA"
		(layer "F.Cu")
		(at 66.7 93.399999 180)
		(descr "Capacitor SMD 0603, IPC-7351 Density Level A")
		(tags "Capacitor 0603")
		(property "Reference" "C79"
			(at -3.26 0.349999 0)
			(layer "F.SilkS")
			(effects
				(font
					(size 0.7 0.7)
					(thickness 0.15)
				)
				(justify right top)
			)
		)
		(property "Value" "C_22u_16V_0603"
			(at -1.42757 1.770288 0)
			(layer "F.Fab")
			(hide yes)
			(effects
				(font
					(size 0.7 0.7)
					(thickness 0.15)
				)
				(justify right top)
			)
		)
		(property "Datasheet" "https://product.samsungsem.com/mlcc/CL10A226MO7JZN.do"
			(at 0 0 0)
			(layer "F.Fab")
			(hide yes)
			(effects
				(font
					(size 1.27 1.27)
					(thickness 0.15)
				)
			)
		)
		(property "Description" "SMD Multilayer Ceramic Capacitor"
			(at 0 0 0)
			(layer "F.Fab")
			(hide yes)
			(effects
				(font
					(size 1.27 1.27)
					(thickness 0.15)
				)
			)
		)
		(property "MPN" "CL10A226MO7JZNC"
			(at 0 0 180)
			(unlocked yes)
			(layer "F.Fab")
			(hide yes)
			(effects
				(font
					(size 1 1)
					(thickness 0.15)
				)
			)
		)
		(property "Manufacturer" "Samsung Electro-Mechanics"
			(at 0 0 180)
			(unlocked yes)
			(layer "F.Fab")
			(hide yes)
			(effects
				(font
					(size 1 1)
					(thickness 0.15)
				)
			)
		)
		(property "License" "Apache-2.0"
			(at 0 0 180)
			(unlocked yes)
			(layer "F.Fab")
			(hide yes)
			(effects
				(font
					(size 1 1)
					(thickness 0.15)
				)
			)
		)
		(property "Author" "Antmicro"
			(at 0 0 180)
			(unlocked yes)
			(layer "F.Fab")
			(hide yes)
			(effects
				(font
					(size 1 1)
					(thickness 0.15)
				)
			)
		)
		(property "Val" "22u"
			(at 0 0 180)
			(unlocked yes)
			(layer "F.Fab")
			(hide yes)
			(effects
				(font
					(size 1 1)
					(thickness 0.15)
				)
			)
		)
		(property "Voltage" "16V"
			(at 0 0 180)
			(unlocked yes)
			(layer "F.Fab")
			(hide yes)
			(effects
				(font
					(size 1 1)
					(thickness 0.15)
				)
			)
		)
		(property "Dielectric" ""
			(at 0 0 180)
			(unlocked yes)
			(layer "F.Fab")
			(hide yes)
			(effects
				(font
					(size 1 1)
					(thickness 0.15)
				)
			)
		)
		(sheetname "/X710-AT2 power/")
		(sheetfile "x710-at2-power.kicad_sch")
		(attr smd)
		(fp_line
			(start -0.15 0.55)
			(end 0.15 0.55)
			(stroke
				(width 0.15)
				(type solid)
			)
			(layer "F.SilkS")
		)
		(fp_line
			(start -0.15 -0.55)
			(end 0.15 -0.55)
			(stroke
				(width 0.15)
				(type solid)
			)
			(layer "F.SilkS")
		)
		(fp_rect
			(start -1.25 -0.65)
			(end 1.25 0.65)
			(stroke
				(width 0.05)
				(type solid)
			)
			(fill no)
			(layer "F.CrtYd")
		)
		(fp_rect
			(start -0.8 -0.45)
			(end 0.8 0.45)
			(stroke
				(width 0.15)
				(type solid)
			)
			(fill no)
			(layer "F.Fab")
		)
		(pad "1" smd roundrect
			(at -0.7 0 180)
			(size 0.8 1.1)
			(layers "F.Cu" "F.Mask" "F.Paste")
			(roundrect_rratio 0.2)
			(net 28 "GND")
			(pintype "passive")
		)
		(pad "2" smd roundrect
			(at 0.7 0 180)
			(size 0.8 1.1)
			(layers "F.Cu" "F.Mask" "F.Paste")
			(roundrect_rratio 0.2)
			(net 6 "DVDD")
			(pintype "passive")
		)
	)
)
